(kicad_pcb
	(version 20260206)
	(generator "pcbnew")
	(generator_version "10.0")
	(general
		(thickness 1.6)
		(legacy_teardrops no)
	)
	(paper "A4")
	(title_block
		(title "dpb — 14545-sa.0730WZS0815.brd")
		(comment 1 "Honey Badger (Wiwynn) / footprints 175-180 of 1066")
	)
	(layers
		(0 "F.Cu" signal "TOP")
		(4 "In1.Cu" signal "L2GND")
		(6 "In2.Cu" signal "L3")
		(8 "In3.Cu" signal "L4VCC")
		(10 "In4.Cu" signal "L5VCC")
		(12 "In5.Cu" signal "L6")
		(14 "In6.Cu" signal "L7GND")
		(2 "B.Cu" signal "BOTTOM")
		(9 "F.Adhes" user "F.Adhesive")
		(11 "B.Adhes" user "B.Adhesive")
		(13 "F.Paste" user "Package Geometry/Pastemask Top")
		(15 "B.Paste" user "Package Geometry/Pastemask Bottom")
		(5 "F.SilkS" user "Ref Des/Silkscreen Top")
		(7 "B.SilkS" user "Ref Des/Silkscreen Bottom")
		(1 "F.Mask" user "Board Geometry/Soldermask Top")
		(3 "B.Mask" user "Board Geometry/Soldermask Bottom")
		(17 "Dwgs.User" user "User.Drawings")
		(19 "Cmts.User" user "User.Comments")
		(21 "Eco1.User" user "User.Eco1")
		(23 "Eco2.User" user "User.Eco2")
		(25 "Edge.Cuts" user "Board Geometry/Outline")
		(27 "Margin" user)
		(31 "F.CrtYd" user "Package Geometry/Place Bound Top")
		(29 "B.CrtYd" user "Package Geometry/Place Bound Bottom")
		(35 "F.Fab" user "Ref Des/Assembly Top")
		(33 "B.Fab" user "Ref Des/Assembly Bottom")
	)
	(footprint ""
		(layer "F.Cu")
		(at 227.499926 -144.159986 180)
		(property "Reference" "LED4"
			(at 0 0 180)
			(layer "F.SilkS")
			(hide yes)
			(effects
				(font
					(size 1.27 1.27)
				)
			)
		)
		(property "Value" "LED-RB-4-GP"
			(at 5.88899 1.80848 180)
			(unlocked yes)
			(layer "F.Fab")
			(hide yes)
			(effects
				(font
					(size 1.016 1.016)
					(thickness 0.1524)
				)
			)
		)
		(property "Device Type" "LED1613-4PH20"
			(at 5.88899 0.28448 180)
			(unlocked yes)
			(layer "F.Fab")
			(hide yes)
			(effects
				(font
					(size 1.016 1.016)
					(thickness 0.1524)
				)
			)
		)
		(duplicate_pad_numbers_are_jumpers no)
		(fp_line
			(start 1.4478 0.9652)
			(end -1.4478 0.9652)
			(stroke
				(width 0.1524)
				(type default)
			)
			(layer "F.SilkS")
		)
		(fp_line
			(start 1.4478 -0.9652)
			(end 1.4478 0.9652)
			(stroke
				(width 0.1524)
				(type default)
			)
			(layer "F.SilkS")
		)
		(fp_line
			(start -1.4478 0.9652)
			(end -1.4478 -0.9652)
			(stroke
				(width 0.1524)
				(type default)
			)
			(layer "F.SilkS")
		)
		(fp_line
			(start -1.4478 0.9652)
			(end -1.4478 -0.9652)
			(stroke
				(width 0.508)
				(type default)
			)
			(layer "F.SilkS")
		)
		(fp_line
			(start -1.4478 -0.9652)
			(end 1.4478 -0.9652)
			(stroke
				(width 0.1524)
				(type default)
			)
			(layer "F.SilkS")
		)
		(fp_rect
			(start -0.8001 0.6477)
			(end 0.8001 -0.6477)
			(stroke
				(width 0)
				(type default)
			)
			(fill no)
			(layer "F.CrtYd")
		)
		(fp_poly
			(pts
				(xy -1.7018 1.2192) (xy -1.7018 -0.06223) (xy -0.8001 -0.06223) (xy -0.8001 0.6477) (xy 0.8001 0.6477)
				(xy 0.8001 -0.6477) (xy -0.8001 -0.6477) (xy -0.8001 -0.0635) (xy -1.7018 -0.0635) (xy -1.7018 -1.2192)
				(xy 1.7018 -1.2192) (xy 1.7018 1.2192)
			)
			(stroke
				(width 0)
				(type default)
			)
			(fill no)
			(layer "F.CrtYd")
		)
		(fp_rect
			(start -1.7018 1.2192)
			(end 1.7018 -1.2192)
			(stroke
				(width 0)
				(type default)
			)
			(fill no)
			(layer "F.Fab")
		)
		(pad "1" smd rect
			(at -0.73025 0.4064 180)
			(size 0.9144 0.6096)
			(layers "F.Cu" "F.Mask" "F.Paste")
			(net "DRV_ACT_NET3")
		)
		(pad "2" smd rect
			(at -0.73025 -0.4064 180)
			(size 0.9144 0.6096)
			(layers "F.Cu" "F.Mask" "F.Paste")
			(net "FLT_NET_HDD3")
		)
		(pad "3" smd rect
			(at 0.73025 -0.4064 180)
			(size 0.9144 0.6096)
			(layers "F.Cu" "F.Mask" "F.Paste")
			(net "FLT_HDD3")
		)
		(pad "4" smd rect
			(at 0.73025 0.4064 180)
			(size 0.9144 0.6096)
			(layers "F.Cu" "F.Mask" "F.Paste")
			(net "DRV_ACT_3")
		)
	)
	(footprint ""
		(layer "F.Cu")
		(at 218.646756 -475.262702 -90)
		(property "Reference" "C104"
			(at 0 0 270)
			(layer "F.SilkS")
			(hide yes)
			(effects
				(font
					(size 1.27 1.27)
				)
			)
		)
		(property "Value" "SCD01U50V2KX-1GP"
			(at 1.1811 -2.7051 270)
			(unlocked yes)
			(layer "F.Fab")
			(hide yes)
			(effects
				(font
					(size 1.016 1.016)
					(thickness 0.1524)
				)
			)
		)
		(property "Device Type" "C402H22"
			(at 1.1811 -4.2291 270)
			(unlocked yes)
			(layer "F.Fab")
			(hide yes)
			(effects
				(font
					(size 1.016 1.016)
					(thickness 0.1524)
				)
			)
		)
		(duplicate_pad_numbers_are_jumpers no)
		(fp_rect
			(start -0.4318 0.9525)
			(end 0.4318 -0.9525)
			(stroke
				(width 0)
				(type default)
			)
			(fill no)
			(layer "F.CrtYd")
		)
		(fp_rect
			(start -0.4318 0.9525)
			(end 0.4318 -0.9525)
			(stroke
				(width 0)
				(type default)
			)
			(fill no)
			(layer "F.Fab")
		)
		(pad "1" smd custom
			(at 0 -0.4445 270)
			(size 0.1524 0.1524)
			(layers "F.Cu" "F.Mask" "F.Paste")
			(net "SAS2X28_DRIVE_RX_N_B0")
			(options
				(clearance outline)
				(anchor circle)
			)
			(primitives
				(gr_poly
					(pts
						(arc
							(start 0.3048 -0.2032)
							(mid 0.275042 -0.275042)
							(end 0.2032 -0.3048)
						)
						(arc
							(start -0.2032 -0.3048)
							(mid -0.275042 -0.275042)
							(end -0.3048 -0.2032)
						)
						(arc
							(start -0.3048 0.2032)
							(mid -0.275042 0.275042)
							(end -0.2032 0.3048)
						)
						(arc
							(start 0.2032 0.3048)
							(mid 0.275042 0.275042)
							(end 0.3048 0.2032)
						)
					)
					(width 0)
					(fill yes)
				)
			)
		)
		(pad "2" smd custom
			(at 0 0.4445 270)
			(size 0.1524 0.1524)
			(layers "F.Cu" "F.Mask" "F.Paste")
			(net "SAS2X28_B_HDD0_RX_-")
			(options
				(clearance outline)
				(anchor circle)
			)
			(primitives
				(gr_poly
					(pts
						(arc
							(start 0.3048 -0.2032)
							(mid 0.275042 -0.275042)
							(end 0.2032 -0.3048)
						)
						(arc
							(start -0.2032 -0.3048)
							(mid -0.275042 -0.275042)
							(end -0.3048 -0.2032)
						)
						(arc
							(start -0.3048 0.2032)
							(mid -0.275042 0.275042)
							(end -0.2032 0.3048)
						)
						(arc
							(start 0.2032 0.3048)
							(mid 0.275042 0.275042)
							(end 0.3048 0.2032)
						)
					)
					(width 0)
					(fill yes)
				)
			)
		)
	)
	(footprint ""
		(layer "F.Cu")
		(at 166.509446 -455.837036)
		(property "Reference" "C354"
			(at 0 0 0)
			(layer "F.SilkS")
			(hide yes)
			(effects
				(font
					(size 1.27 1.27)
				)
			)
		)
		(property "Value" "SCD1U16V2KX-3GP"
			(at 1.1811 -2.7051 0)
			(unlocked yes)
			(layer "F.Fab")
			(hide yes)
			(effects
				(font
					(size 1.016 1.016)
					(thickness 0.1524)
				)
			)
		)
		(property "Device Type" "C402H22"
			(at 1.1811 -4.2291 0)
			(unlocked yes)
			(layer "F.Fab")
			(hide yes)
			(effects
				(font
					(size 1.016 1.016)
					(thickness 0.1524)
				)
			)
		)
		(duplicate_pad_numbers_are_jumpers no)
		(fp_rect
			(start -0.4318 0.9525)
			(end 0.4318 -0.9525)
			(stroke
				(width 0)
				(type default)
			)
			(fill no)
			(layer "F.CrtYd")
		)
		(fp_rect
			(start -0.4318 0.9525)
			(end 0.4318 -0.9525)
			(stroke
				(width 0)
				(type default)
			)
			(fill no)
			(layer "F.Fab")
		)
		(pad "1" smd custom
			(at 0 -0.4445)
			(size 0.1524 0.1524)
			(layers "F.Cu" "F.Mask" "F.Paste")
			(net "P5VB_SENSE")
			(options
				(clearance outline)
				(anchor circle)
			)
			(primitives
				(gr_poly
					(pts
						(arc
							(start 0.3048 -0.2032)
							(mid 0.275042 -0.275042)
							(end 0.2032 -0.3048)
						)
						(arc
							(start -0.2032 -0.3048)
							(mid -0.275042 -0.275042)
							(end -0.3048 -0.2032)
						)
						(arc
							(start -0.3048 0.2032)
							(mid -0.275042 0.275042)
							(end -0.2032 0.3048)
						)
						(arc
							(start 0.2032 0.3048)
							(mid 0.275042 0.275042)
							(end 0.3048 0.2032)
						)
					)
					(width 0)
					(fill yes)
				)
			)
		)
		(pad "2" smd custom
			(at 0 0.4445)
			(size 0.1524 0.1524)
			(layers "F.Cu" "F.Mask" "F.Paste")
			(net "GND")
			(options
				(clearance outline)
				(anchor circle)
			)
			(primitives
				(gr_poly
					(pts
						(arc
							(start 0.3048 -0.2032)
							(mid 0.275042 -0.275042)
							(end 0.2032 -0.3048)
						)
						(arc
							(start -0.2032 -0.3048)
							(mid -0.275042 -0.275042)
							(end -0.3048 -0.2032)
						)
						(arc
							(start -0.3048 0.2032)
							(mid -0.275042 0.275042)
							(end -0.2032 0.3048)
						)
						(arc
							(start 0.2032 0.3048)
							(mid 0.275042 0.275042)
							(end 0.3048 0.2032)
						)
					)
					(width 0)
					(fill yes)
				)
			)
		)
	)
	(footprint ""
		(layer "F.Cu")
		(at 193.246756 -495.862102 -90)
		(property "Reference" "Q1"
			(at 0 0 270)
			(layer "F.SilkS")
			(hide yes)
			(effects
				(font
					(size 1.27 1.27)
				)
			)
		)
		(property "Value" "2N7002DW-7F-GP"
			(at -2.3622 -8.2042 270)
			(unlocked yes)
			(layer "F.Fab")
			(hide yes)
			(effects
				(font
					(size 1.016 1.016)
					(thickness 0.1524)
				)
			)
		)
		(property "Device Type" "SOT-363H44"
			(at -2.3622 -10.1092 270)
			(unlocked yes)
			(layer "F.Fab")
			(hide yes)
			(effects
				(font
					(size 1.016 1.016)
					(thickness 0.1524)
				)
			)
		)
		(duplicate_pad_numbers_are_jumpers no)
		(fp_line
			(start -1.4478 1.7018)
			(end 1.4478 1.7018)
			(stroke
				(width 0.1524)
				(type default)
			)
			(layer "F.SilkS")
		)
		(fp_line
			(start 1.4478 1.7018)
			(end 1.4478 -1.7018)
			(stroke
				(width 0.1524)
				(type default)
			)
			(layer "F.SilkS")
		)
		(fp_line
			(start -1.27 1.524)
			(end -1.27 0.6604)
			(stroke
				(width 0.4826)
				(type default)
			)
			(layer "F.SilkS")
		)
		(fp_line
			(start -1.4478 -1.7018)
			(end -1.4478 1.7018)
			(stroke
				(width 0.1524)
				(type default)
			)
			(layer "F.SilkS")
		)
		(fp_line
			(start 1.4478 -1.7018)
			(end -1.4478 -1.7018)
			(stroke
				(width 0.1524)
				(type default)
			)
			(layer "F.SilkS")
		)
		(fp_poly
			(pts
				(xy -1.524 -1.778) (xy 1.524 -1.778) (xy 1.524 1.778) (xy -1.524 1.778)
			)
			(stroke
				(width 0)
				(type default)
			)
			(fill no)
			(layer "F.CrtYd")
		)
		(fp_poly
			(pts
				(xy -1.524 -1.778) (xy 1.524 -1.778) (xy 1.524 1.778) (xy -1.524 1.778)
			)
			(stroke
				(width 0)
				(type default)
			)
			(fill no)
			(layer "F.Fab")
		)
		(pad "1" smd rect
			(at -0.65024 0.9398 270)
			(size 0.4064 1.016)
			(layers "F.Cu" "F.Mask" "F.Paste")
			(net "GND")
		)
		(pad "2" smd rect
			(at 0 0.9398 270)
			(size 0.4064 1.016)
			(layers "F.Cu" "F.Mask" "F.Paste")
			(net "SW_PWR_R_HDD0")
		)
		(pad "3" smd rect
			(at 0.65024 0.9398 270)
			(size 0.4064 1.016)
			(layers "F.Cu" "F.Mask" "F.Paste")
			(net "SW_HDD0_P")
		)
		(pad "4" smd rect
			(at 0.65024 -0.9398 270)
			(size 0.4064 1.016)
			(layers "F.Cu" "F.Mask" "F.Paste")
			(net "GND")
		)
		(pad "5" smd rect
			(at 0 -0.9398 270)
			(size 0.4064 1.016)
			(layers "F.Cu" "F.Mask" "F.Paste")
			(net "SW_HDD0_G")
		)
		(pad "6" smd rect
			(at -0.65024 -0.9398 270)
			(size 0.4064 1.016)
			(layers "F.Cu" "F.Mask" "F.Paste")
			(net "SW_HDD0_R")
		)
	)
	(footprint ""
		(layer "F.Cu")
		(at 99.186746 -9.9187 90)
		(property "Reference" "Q30"
			(at 0 0 90)
			(layer "F.SilkS")
			(hide yes)
			(effects
				(font
					(size 1.27 1.27)
				)
			)
		)
		(property "Value" "2N7002DW-7F-GP"
			(at -2.3622 -8.2042 90)
			(unlocked yes)
			(layer "F.Fab")
			(hide yes)
			(effects
				(font
					(size 1.016 1.016)
					(thickness 0.1524)
				)
			)
		)
		(property "Device Type" "SOT-363H44"
			(at -2.3622 -10.1092 90)
			(unlocked yes)
			(layer "F.Fab")
			(hide yes)
			(effects
				(font
					(size 1.016 1.016)
					(thickness 0.1524)
				)
			)
		)
		(duplicate_pad_numbers_are_jumpers no)
		(fp_line
			(start 1.4478 -1.7018)
			(end -1.4478 -1.7018)
			(stroke
				(width 0.1524)
				(type default)
			)
			(layer "F.SilkS")
		)
		(fp_line
			(start -1.4478 -1.7018)
			(end -1.4478 1.7018)
			(stroke
				(width 0.1524)
				(type default)
			)
			(layer "F.SilkS")
		)
		(fp_line
			(start -1.27 1.524)
			(end -1.27 0.6604)
			(stroke
				(width 0.4826)
				(type default)
			)
			(layer "F.SilkS")
		)
		(fp_line
			(start 1.4478 1.7018)
			(end 1.4478 -1.7018)
			(stroke
				(width 0.1524)
				(type default)
			)
			(layer "F.SilkS")
		)
		(fp_line
			(start -1.4478 1.7018)
			(end 1.4478 1.7018)
			(stroke
				(width 0.1524)
				(type default)
			)
			(layer "F.SilkS")
		)
		(fp_poly
			(pts
				(xy -1.524 -1.778) (xy 1.524 -1.778) (xy 1.524 1.778) (xy -1.524 1.778)
			)
			(stroke
				(width 0)
				(type default)
			)
			(fill no)
			(layer "F.CrtYd")
		)
		(fp_poly
			(pts
				(xy -1.524 -1.778) (xy 1.524 -1.778) (xy 1.524 1.778) (xy -1.524 1.778)
			)
			(stroke
				(width 0)
				(type default)
			)
			(fill no)
			(layer "F.Fab")
		)
		(pad "1" smd rect
			(at -0.65024 0.9398 90)
			(size 0.4064 1.016)
			(layers "F.Cu" "F.Mask" "F.Paste")
			(net "GND")
		)
		(pad "2" smd rect
			(at 0 0.9398 90)
			(size 0.4064 1.016)
			(layers "F.Cu" "F.Mask" "F.Paste")
			(net "SW_PWR_R_HDD14")
		)
		(pad "3" smd rect
			(at 0.65024 0.9398 90)
			(size 0.4064 1.016)
			(layers "F.Cu" "F.Mask" "F.Paste")
			(net "SW_HDD14_P")
		)
		(pad "4" smd rect
			(at 0.65024 -0.9398 90)
			(size 0.4064 1.016)
			(layers "F.Cu" "F.Mask" "F.Paste")
			(net "GND")
		)
		(pad "5" smd rect
			(at 0 -0.9398 90)
			(size 0.4064 1.016)
			(layers "F.Cu" "F.Mask" "F.Paste")
			(net "SW_HDD14_G")
		)
		(pad "6" smd rect
			(at -0.65024 -0.9398 90)
			(size 0.4064 1.016)
			(layers "F.Cu" "F.Mask" "F.Paste")
			(net "SW_HDD14_R")
		)
	)
	(footprint ""
		(layer "F.Cu")
		(at 33.02 -346.71 90)
		(property "Reference" "R257"
			(at 0 0 90)
			(layer "F.SilkS")
			(hide yes)
			(effects
				(font
					(size 1.27 1.27)
				)
			)
		)
		(property "Value" "330R2F-GP"
			(at 0.064008 -3.993896 90)
			(unlocked yes)
			(layer "F.Fab")
			(hide yes)
			(effects
				(font
					(size 1.016 1.016)
					(thickness 0.1524)
				)
			)
		)
		(property "Device Type" "R402H16"
			(at 0.064008 -5.517896 90)
			(unlocked yes)
			(layer "F.Fab")
			(hide yes)
			(effects
				(font
					(size 1.016 1.016)
					(thickness 0.1524)
				)
			)
		)
		(duplicate_pad_numbers_are_jumpers no)
		(fp_line
			(start 0.508 -0.9398)
			(end -0.508 -0.9398)
			(stroke
				(width 0.1524)
				(type default)
			)
			(layer "F.SilkS")
		)
		(fp_line
			(start -0.508 -0.9398)
			(end -0.508 0.9398)
			(stroke
				(width 0.1524)
				(type default)
			)
			(layer "F.SilkS")
		)
		(fp_rect
			(start -0.508 0.9398)
			(end 0.508 -0.9398)
			(stroke
				(width 0)
				(type default)
			)
			(fill no)
			(layer "F.CrtYd")
		)
		(fp_rect
			(start -0.508 0.9398)
			(end 0.508 -0.9398)
			(stroke
				(width 0)
				(type default)
			)
			(fill no)
			(layer "F.Fab")
		)
		(pad "1" smd custom
			(at 0 -0.4445 90)
			(size 0.1397 0.1397)
			(layers "F.Cu" "F.Mask" "F.Paste")
			(net "P3V3_HDD11_LED")
			(options
				(clearance outline)
				(anchor circle)
			)
			(primitives
				(gr_poly
					(pts
						(arc
							(start -0.1778 -0.2794)
							(mid -0.249642 -0.249642)
							(end -0.2794 -0.1778)
						)
						(arc
							(start -0.2794 0.1778)
							(mid -0.249642 0.249642)
							(end -0.1778 0.2794)
						)
						(arc
							(start 0.1778 0.2794)
							(mid 0.249642 0.249642)
							(end 0.2794 0.1778)
						)
						(arc
							(start 0.2794 -0.1778)
							(mid 0.249642 -0.249642)
							(end 0.1778 -0.2794)
						)
					)
					(width 0)
					(fill yes)
				)
			)
		)
		(pad "2" smd custom
			(at 0 0.4445 90)
			(size 0.1397 0.1397)
			(layers "F.Cu" "F.Mask" "F.Paste")
			(net "FLT_HDD11")
			(options
				(clearance outline)
				(anchor circle)
			)
			(primitives
				(gr_poly
					(pts
						(arc
							(start -0.1778 -0.2794)
							(mid -0.249642 -0.249642)
							(end -0.2794 -0.1778)
						)
						(arc
							(start -0.2794 0.1778)
							(mid -0.249642 0.249642)
							(end -0.1778 0.2794)
						)
						(arc
							(start 0.1778 0.2794)
							(mid 0.249642 0.249642)
							(end 0.2794 0.1778)
						)
						(arc
							(start 0.2794 -0.1778)
							(mid 0.249642 -0.249642)
							(end 0.1778 -0.2794)
						)
					)
					(width 0)
					(fill yes)
				)
			)
		)
	)
)
